# T6G (Grand Teton) — schematic netlist excerpt (pin names and nets, part order shuffled) for the footprints in the layout excerpt that follows; sources: Cadence DE-HDL packaged netlist, KiCad conversion of 04192023_DAF0TMB3IC0_F0TG_MB_C_brd_V02_OCP.brd

R241  Q_RES  0 5% CHIP  pkg 0402LF  page 81 : A = RST_CPU0_RESETL_N ; B = FM_RST_CPU0_RESETL_N
R3470  Q_RES  1K 1% CHIP  pkg 0402LF  page 126 : A = P3V3_AUX ; B = GPU_WP_HW_CTRL_N
R916  Q_RES  10K 1% CHIP  pkg 0201LF  page 353 : A = GPIO2_RT_CPU1_P3 ; B = GND

(kicad_pcb
	(version 20260206)
	(generator "pcbnew")
	(generator_version "10.0")
	(general
		(thickness 1.6)
		(legacy_teardrops no)
	)
	(paper "A4")
	(title_block
		(title "04192023_DAF0TMB3IC0_F0TG_MB_C_brd_V02_OCP.brd")
		(comment 1 "Grand Teton / footprints 116-118 of 8354")
	)
	(layers
		(0 "F.Cu" signal "TOP")
		(4 "In1.Cu" signal "GND")
		(6 "In2.Cu" signal "IN1")
		(8 "In3.Cu" signal "GND1")
		(10 "In4.Cu" signal "IN2")
		(12 "In5.Cu" signal "GND2")
		(14 "In6.Cu" signal "IN3")
		(16 "In7.Cu" signal "GND3")
		(18 "In8.Cu" signal "VCC")
		(20 "In9.Cu" signal "VCC1")
		(22 "In10.Cu" signal "GND4")
		(24 "In11.Cu" signal "IN4")
		(26 "In12.Cu" signal "GND5")
		(28 "In13.Cu" signal "IN5")
		(30 "In14.Cu" signal "GND6")
		(32 "In15.Cu" signal "IN6")
		(34 "In16.Cu" signal "GND7")
		(2 "B.Cu" signal "BOTTOM")
		(9 "F.Adhes" user "F.Adhesive")
		(11 "B.Adhes" user "B.Adhesive")
		(13 "F.Paste" user "Package Geometry/Pastemask Top")
		(15 "B.Paste" user "Package Geometry/Pastemask Bottom")
		(5 "F.SilkS" user "Ref Des/Silkscreen Top")
		(7 "B.SilkS" user "Ref Des/Silkscreen Bottom")
		(1 "F.Mask" user "Board Geometry/Soldermask Top")
		(3 "B.Mask" user "Board Geometry/Soldermask Bottom")
		(17 "Dwgs.User" user "User.Drawings")
		(19 "Cmts.User" user "User.Comments")
		(21 "Eco1.User" user "User.Eco1")
		(23 "Eco2.User" user "User.Eco2")
		(25 "Edge.Cuts" user "Board Geometry/Outline")
		(27 "Margin" user)
		(31 "F.CrtYd" user "Package Geometry/Place Bound Top")
		(29 "B.CrtYd" user "Package Geometry/Place Bound Bottom")
		(35 "F.Fab" user "Ref Des/Assembly Top")
		(33 "B.Fab" user "Ref Des/Assembly Bottom")
	)
	(footprint ""
		(layer "F.Cu")
		(at 183.007 -129.377948 -90)
		(property "Reference" "R241"
			(at 0 0 270)
			(layer "F.SilkS")
			(hide yes)
			(effects
				(font
					(size 1.27 1.27)
				)
			)
		)
		(property "Value" ""
			(at 0 0 270)
			(layer "F.Fab")
			(effects
				(font
					(size 1.27 1.27)
				)
			)
		)
		(duplicate_pad_numbers_are_jumpers no)
		(fp_line
			(start -0.7874 0.4064)
			(end -0.7874 -0.4064)
			(stroke
				(width 0.1524)
				(type default)
			)
			(layer "F.SilkS")
		)
		(fp_line
			(start 0.7874 0.4064)
			(end -0.7874 0.4064)
			(stroke
				(width 0.1524)
				(type default)
			)
			(layer "F.SilkS")
		)
		(fp_line
			(start -0.7874 -0.4064)
			(end 0.7874 -0.4064)
			(stroke
				(width 0.1524)
				(type default)
			)
			(layer "F.SilkS")
		)
		(fp_line
			(start 0.7874 -0.4064)
			(end 0.7874 0.4064)
			(stroke
				(width 0.1524)
				(type default)
			)
			(layer "F.SilkS")
		)
		(fp_line
			(start -0.67945 0.3048)
			(end -0.67945 -0.305054)
			(stroke
				(width 0.1)
				(type default)
			)
			(layer "F.Fab")
		)
		(fp_line
			(start -0.12065 0.3048)
			(end -0.67945 0.3048)
			(stroke
				(width 0.1)
				(type default)
			)
			(layer "F.Fab")
		)
		(fp_line
			(start 0.120396 0.3048)
			(end 0.120396 0.2794)
			(stroke
				(width 0.1)
				(type default)
			)
			(layer "F.Fab")
		)
		(fp_line
			(start 0.67945 0.3048)
			(end 0.120396 0.3048)
			(stroke
				(width 0.1)
				(type default)
			)
			(layer "F.Fab")
		)
		(fp_line
			(start -0.12065 0.2794)
			(end -0.12065 0.3048)
			(stroke
				(width 0.1)
				(type default)
			)
			(layer "F.Fab")
		)
		(fp_line
			(start 0.120396 0.2794)
			(end -0.12065 0.2794)
			(stroke
				(width 0.1)
				(type default)
			)
			(layer "F.Fab")
		)
		(fp_line
			(start -0.12065 -0.2794)
			(end 0.12065 -0.2794)
			(stroke
				(width 0.1)
				(type default)
			)
			(layer "F.Fab")
		)
		(fp_line
			(start 0.12065 -0.2794)
			(end 0.12065 -0.3048)
			(stroke
				(width 0.1)
				(type default)
			)
			(layer "F.Fab")
		)
		(fp_line
			(start 0.12065 -0.3048)
			(end 0.67945 -0.3048)
			(stroke
				(width 0.1)
				(type default)
			)
			(layer "F.Fab")
		)
		(fp_line
			(start 0.67945 -0.3048)
			(end 0.67945 0.3048)
			(stroke
				(width 0.1)
				(type default)
			)
			(layer "F.Fab")
		)
		(fp_line
			(start -0.67945 -0.305054)
			(end -0.12065 -0.305054)
			(stroke
				(width 0.1)
				(type default)
			)
			(layer "F.Fab")
		)
		(fp_line
			(start -0.12065 -0.305054)
			(end -0.12065 -0.2794)
			(stroke
				(width 0.1)
				(type default)
			)
			(layer "F.Fab")
		)
		(pad "1" smd circle
			(at -0.40005 0 270)
			(size 0 0)
			(layers "F.Cu" "F.Mask" "F.Paste")
			(net "RST_CPU0_RESETL_N")
		)
		(pad "2" smd circle
			(at 0.40005 0 270)
			(size 0 0)
			(layers "F.Cu" "F.Mask" "F.Paste")
			(net "FM_RST_CPU0_RESETL_N")
		)
	)
	(footprint ""
		(layer "F.Cu")
		(at 439.072782 -435.27726 -90)
		(property "Reference" "R3470"
			(at 0 0 270)
			(layer "F.SilkS")
			(hide yes)
			(effects
				(font
					(size 1.27 1.27)
				)
			)
		)
		(property "Value" ""
			(at 0 0 270)
			(layer "F.Fab")
			(effects
				(font
					(size 1.27 1.27)
				)
			)
		)
		(duplicate_pad_numbers_are_jumpers no)
		(fp_line
			(start -0.7874 0.4064)
			(end -0.7874 -0.4064)
			(stroke
				(width 0.1524)
				(type default)
			)
			(layer "F.SilkS")
		)
		(fp_line
			(start 0.7874 0.4064)
			(end -0.7874 0.4064)
			(stroke
				(width 0.1524)
				(type default)
			)
			(layer "F.SilkS")
		)
		(fp_line
			(start -0.7874 -0.4064)
			(end 0.7874 -0.4064)
			(stroke
				(width 0.1524)
				(type default)
			)
			(layer "F.SilkS")
		)
		(fp_line
			(start 0.7874 -0.4064)
			(end 0.7874 0.4064)
			(stroke
				(width 0.1524)
				(type default)
			)
			(layer "F.SilkS")
		)
		(fp_line
			(start -0.67945 0.3048)
			(end -0.67945 -0.305054)
			(stroke
				(width 0.1)
				(type default)
			)
			(layer "F.Fab")
		)
		(fp_line
			(start -0.12065 0.3048)
			(end -0.67945 0.3048)
			(stroke
				(width 0.1)
				(type default)
			)
			(layer "F.Fab")
		)
		(fp_line
			(start 0.120396 0.3048)
			(end 0.120396 0.2794)
			(stroke
				(width 0.1)
				(type default)
			)
			(layer "F.Fab")
		)
		(fp_line
			(start 0.67945 0.3048)
			(end 0.120396 0.3048)
			(stroke
				(width 0.1)
				(type default)
			)
			(layer "F.Fab")
		)
		(fp_line
			(start -0.12065 0.2794)
			(end -0.12065 0.3048)
			(stroke
				(width 0.1)
				(type default)
			)
			(layer "F.Fab")
		)
		(fp_line
			(start 0.120396 0.2794)
			(end -0.12065 0.2794)
			(stroke
				(width 0.1)
				(type default)
			)
			(layer "F.Fab")
		)
		(fp_line
			(start -0.12065 -0.2794)
			(end 0.12065 -0.2794)
			(stroke
				(width 0.1)
				(type default)
			)
			(layer "F.Fab")
		)
		(fp_line
			(start 0.12065 -0.2794)
			(end 0.12065 -0.3048)
			(stroke
				(width 0.1)
				(type default)
			)
			(layer "F.Fab")
		)
		(fp_line
			(start 0.12065 -0.3048)
			(end 0.67945 -0.3048)
			(stroke
				(width 0.1)
				(type default)
			)
			(layer "F.Fab")
		)
		(fp_line
			(start 0.67945 -0.3048)
			(end 0.67945 0.3048)
			(stroke
				(width 0.1)
				(type default)
			)
			(layer "F.Fab")
		)
		(fp_line
			(start -0.67945 -0.305054)
			(end -0.12065 -0.305054)
			(stroke
				(width 0.1)
				(type default)
			)
			(layer "F.Fab")
		)
		(fp_line
			(start -0.12065 -0.305054)
			(end -0.12065 -0.2794)
			(stroke
				(width 0.1)
				(type default)
			)
			(layer "F.Fab")
		)
		(pad "1" smd circle
			(at -0.40005 0 270)
			(size 0 0)
			(layers "F.Cu" "F.Mask" "F.Paste")
			(net "P3V3_AUX")
		)
		(pad "2" smd circle
			(at 0.40005 0 270)
			(size 0 0)
			(layers "F.Cu" "F.Mask" "F.Paste")
			(net "GPU_WP_HW_CTRL_N")
		)
	)
	(footprint ""
		(layer "F.Cu")
		(at 110.365794 -385.58216)
		(property "Reference" "R916"
			(at 0 0 0)
			(layer "F.SilkS")
			(hide yes)
			(effects
				(font
					(size 1.27 1.27)
				)
			)
		)
		(property "Value" ""
			(at 0 0 0)
			(layer "F.Fab")
			(effects
				(font
					(size 1.27 1.27)
				)
			)
		)
		(duplicate_pad_numbers_are_jumpers no)
		(fp_line
			(start -0.32512 -0.175006)
			(end 0.32512 -0.175006)
			(stroke
				(width 0.1)
				(type default)
			)
			(layer "F.Fab")
		)
		(fp_line
			(start -0.32512 0.175006)
			(end -0.32512 -0.175006)
			(stroke
				(width 0.1)
				(type default)
			)
			(layer "F.Fab")
		)
		(fp_line
			(start 0.32512 -0.175006)
			(end 0.32512 0.175006)
			(stroke
				(width 0.1)
				(type default)
			)
			(layer "F.Fab")
		)
		(fp_line
			(start 0.32512 0.175006)
			(end -0.32512 0.175006)
			(stroke
				(width 0.1)
				(type default)
			)
			(layer "F.Fab")
		)
		(pad "1" smd rect
			(at -0.2667 0)
			(size 0.3048 0.381)
			(layers "F.Cu" "F.Mask" "F.Paste")
			(net "GPIO2_RT_CPU1_P3")
		)
		(pad "2" smd rect
			(at 0.2667 0 180)
			(size 0.3048 0.381)
			(layers "F.Cu" "F.Mask" "F.Paste")
			(net "GND")
		)
	)
)
